# S9S_MB_2U (Grand Teton) — schematic netlist excerpt (pin names and nets, part order shuffled) for the footprints in the layout excerpt that follows; sources: Cadence DE-HDL packaged netlist, KiCad conversion of 03242023_DA0F0TMBIJ0_F0T_Motherboard_J_brd_V01_OCP.brd

J11  SCONN288_ADR50017P130CC  SCONN288_ADR50017-P130CC IO  pkg DDR288S_1-1VXB  page 92
  VIN_BULK0  = P12V_S3_AUX_CPU0_NVDIMM
  RFU0  = TP_CHF_CPU0_DIMM1_FRU_0
  VIN_MGMT  = P3V3_AUX
  HSCL  = I3C_SPD_DDREFGH_CPU0_LVC1_SCL_2
  HSDA  = I3C_SPD_DDREFGH_CPU0_LVC1_SDA
  VSS0  = GND
  DQ0_A  = M_F_CPU0_SA_DQ<0>
  VSS1  = GND
  DQ1_A  = M_F_CPU0_SA_DQ<1>
  VSS2  = GND
  DQS0_A_T  = M_F_CPU0_SA_DQS_DP<0>
  DQS0_A_C  = M_F_CPU0_SA_DQS_DN<0>
  VSS3  = GND
  DQ4_A  = M_F_CPU0_SA_DQ<4>
  VSS4  = GND
  DQ5_A  = M_F_CPU0_SA_DQ<5>
  VSS5  = GND
  DQ8_A  = M_F_CPU0_SA_DQ<8>
  VSS6  = GND
  DQ9_A  = M_F_CPU0_SA_DQ<9>
  VSS7  = GND
  DQS1_A_T  = M_F_CPU0_SA_DQS_DP<1>
  DQS1_A_C  = M_F_CPU0_SA_DQS_DN<1>
  VSS8  = GND
  DQ12_A  = M_F_CPU0_SA_DQ<12>
  VSS9  = GND
  DQ13_A  = M_F_CPU0_SA_DQ<13>
  VSS10  = GND
  DQ16_A  = M_F_CPU0_SA_DQ<16>
  VSS11  = GND
  DQ17_A  = M_F_CPU0_SA_DQ<17>
  VSS12  = GND
  DQS2_A_T  = M_F_CPU0_SA_DQS_DP<2>
  DQS2_A_C  = M_F_CPU0_SA_DQS_DN<2>
  VSS13  = GND
  DQ20_A  = M_F_CPU0_SA_DQ<20>
  VSS14  = GND
  DQ21_A  = M_F_CPU0_SA_DQ<21>
  VSS15  = GND
  DQ24_A  = M_F_CPU0_SA_DQ<24>
  VSS16  = GND
  DQ25_A  = M_F_CPU0_SA_DQ<25>
  VSS17  = GND
  DQS3_A_T  = M_F_CPU0_SA_DQS_DP<3>
  DQS3_A_C  = M_F_CPU0_SA_DQS_DN<3>
  VSS18  = GND
  DQ28_A  = M_F_CPU0_SA_DQ<28>
  VSS19  = GND
  DQ29_A  = M_F_CPU0_SA_DQ<29>
  VSS20  = GND
  CB0_A  = M_F_CPU0_SA_CB<0>
  VSS21  = GND
  CB1_A  = M_F_CPU0_SA_CB<1>
  VSS22  = GND
  DQS4_A_T  = M_F_CPU0_SA_DQS_DP<4>
  DQS4_A_C  = M_F_CPU0_SA_DQS_DN<4>
  VSS23  = GND
  CB4_A  = M_F_CPU0_SA_CB<4>
  VSS24  = GND
  CB5_A  = M_F_CPU0_SA_CB<5>
  VSS25  = GND
  ALERT_N  = M_F_CPU0_ALERT_N
  VSS26  = GND
  CS0_A_N  = M_F_CPU0_SA_CS_N<0>
  VSS27  = GND
  CA0_A  = M_F_CPU0_SA_CA<0>
  VSS28  = GND
  CA2_A  = M_F_CPU0_SA_CA<2>
  VSS29  = GND
  CA4_A  = M_F_CPU0_SA_CA<4>
  VSS30  = GND
  CA6_A  = M_F_CPU0_SA_CA<6>
  VSS31  = GND
  PAR_A  = M_F_CPU0_SA_PAR
  VSS32  = GND
  CA0_B  = M_F_CPU0_SB_CA<0>
  VSS33  = GND
  CA2_B  = M_F_CPU0_SB_CA<2>
  VSS34  = GND
  CA4_B  = M_F_CPU0_SB_CA<4>
  VSS35  = GND
  CA6_B  = M_F_CPU0_SB_CA<6>
  VSS36  = GND
  CS0_B_N  = M_F_CPU0_SB_CS_N<0>
  VSS37  = GND
  \lbd||rsp_a_n\  = M_F_CPU0_SA_RSP<0>
  \lbs||rsp_b_n\  = M_F_CPU0_SB_RSP<0>
  VSS38  = GND
  CB4_B  = M_F_CPU0_SB_CB<4>
  VSS39  = GND
  CB5_B  = M_F_CPU0_SB_CB<5>
  VSS40  = GND
  \dqs9_b_t||tdqs9_b_t||dbi4_b_n\  = M_F_CPU0_SB_DQS_DP<9>
  \dqs9_b_c||tdqs9_b_c\  = M_F_CPU0_SB_DQS_DN<9>
  VSS41  = GND
  CB0_B  = M_F_CPU0_SB_CB<0>
  VSS42  = GND
  CB1_B  = M_F_CPU0_SB_CB<1>
  VSS43  = GND
  DQ0_B  = M_F_CPU0_SB_DQ<0>
  VSS44  = GND
  DQ1_B  = M_F_CPU0_SB_DQ<1>
  VSS45  = GND
  DQS0_B_T  = M_F_CPU0_SB_DQS_DP<0>
  DQS0_B_C  = M_F_CPU0_SB_DQS_DN<0>
  VSS46  = GND
  DQ4_B  = M_F_CPU0_SB_DQ<4>
  VSS47  = GND
  DQ5_B  = M_F_CPU0_SB_DQ<5>
  VSS48  = GND
  DQ8_B  = M_F_CPU0_SB_DQ<8>
  VSS49  = GND
  DQ9_B  = M_F_CPU0_SB_DQ<9>
  VSS50  = GND
  DQS1_B_T  = M_F_CPU0_SB_DQS_DP<1>
  DQS1_B_C  = M_F_CPU0_SB_DQS_DN<1>
  VSS51  = GND
  DQ12_B  = M_F_CPU0_SB_DQ<12>
  VSS52  = GND
  DQ13_B  = M_F_CPU0_SB_DQ<13>
  VSS53  = GND
  DQ16_B  = M_F_CPU0_SB_DQ<16>
  VSS54  = GND
  DQ17_B  = M_F_CPU0_SB_DQ<17>
  VSS55  = GND
  DQS2_B_T  = M_F_CPU0_SB_DQS_DP<2>
  DQS2_B_C  = M_F_CPU0_SB_DQS_DN<2>
  VSS56  = GND
  DQ20_B  = M_F_CPU0_SB_DQ<20>
  VSS57  = GND
  DQ21_B  = M_F_CPU0_SB_DQ<21>
  VSS58  = GND
  DQ24_B  = M_F_CPU0_SB_DQ<24>
  VSS59  = GND
  DQ25_B  = M_F_CPU0_SB_DQ<25>
  VSS60  = GND
  DQS3_B_T  = M_F_CPU0_SB_DQS_DP<3>
  DQS3_B_C  = M_F_CPU0_SB_DQS_DN<3>
  VSS61  = GND
  DQ28_B  = M_F_CPU0_SB_DQ<28>
  VSS62  = GND
  DQ29_B  = M_F_CPU0_SB_DQ<29>
  VSS63  = GND
  RFU1  = TP_CHF_CPU0_DIMM1_FRU_1
  VIN_BULK1  = P12V_S3_AUX_CPU0_NVDIMM
  VIN_BULK2  = P12V_S3_AUX_CPU0_NVDIMM
  \pwr_good||fail_n\  = PWRGD_CHF_CPU0_DIMM1
  HSA  = PD_CHF_CPU0_DIMM1_SAA
  RFU2  = TP_CHF_CPU0_DIMM1_FRU_2
  RFU3  = TP_CHF_CPU0_DIMM1_FRU_3
  VSS64  = GND
  DQ2_A  = M_F_CPU0_SA_DQ<2>
  VSS65  = GND
  DQ3_A  = M_F_CPU0_SA_DQ<3>
  VSS66  = GND
  \dqs5_a_c||tdqs5_a_c||dqs5_a_t||tdqs5_a_t\  = M_F_CPU0_SA_DQS_DN<5>
  \dqs5_a_t||tdqs5_a_t\  = M_F_CPU0_SA_DQS_DP<5>
  VSS67  = GND
  DQ6_A  = M_F_CPU0_SA_DQ<6>
  VSS68  = GND
  DQ7_A  = M_F_CPU0_SA_DQ<7>
  VSS69  = GND
  DQ10_A  = M_F_CPU0_SA_DQ<10>
  VSS70  = GND
  DQ11_A  = M_F_CPU0_SA_DQ<11>
  VSS71  = GND
  \dqs6_a_c||tdqs6_a_c||dqs6_a_t||tdqs6_a_t\  = M_F_CPU0_SA_DQS_DN<6>
  \dqs6_a_t||tdqs6_a_t\  = M_F_CPU0_SA_DQS_DP<6>
  VSS72  = GND
  DQ14_A  = M_F_CPU0_SA_DQ<14>
  VSS73  = GND
  DQ15_A  = M_F_CPU0_SA_DQ<15>
  VSS74  = GND
  DQ18_A  = M_F_CPU0_SA_DQ<18>
  VSS75  = GND
  DQ19_A  = M_F_CPU0_SA_DQ<19>
  VSS76  = GND
  \dqs7_a_c||tdqs7_a_c\  = M_F_CPU0_SA_DQS_DN<7>
  \dqs7_a_t||tdqs7_a_t\  = M_F_CPU0_SA_DQS_DP<7>
  VSS77  = GND
  DQ22_A  = M_F_CPU0_SA_DQ<22>
  VSS78  = GND
  DQ23_A  = M_F_CPU0_SA_DQ<23>
  VSS79  = GND
  DQ26_A  = M_F_CPU0_SA_DQ<26>
  VSS80  = GND
  DQ27_A  = M_F_CPU0_SA_DQ<27>
  VSS81  = GND
  \dqs8_a_c||tdqs8_a_c\  = M_F_CPU0_SA_DQS_DN<8>
  \dqs8_a_t||tdqs8_a_t\  = M_F_CPU0_SA_DQS_DP<8>
  VSS82  = GND
  DQ30_A  = M_F_CPU0_SA_DQ<30>
  VSS83  = GND
  DQ31_A  = M_F_CPU0_SA_DQ<31>
  VSS84  = GND
  CB2_A  = M_F_CPU0_SA_CB<2>
  VSS85  = GND
  CB3_A  = M_F_CPU0_SA_CB<3>
  VSS86  = GND
  \dqs9_a_c||tdqs9_a_c\  = M_F_CPU0_SA_DQS_DN<9>
  \dqs9_a_t||tdqs9_a_t\  = M_F_CPU0_SA_DQS_DP<9>
  VSS87  = GND
  CB6_A  = M_F_CPU0_SA_CB<6>
  VSS88  = GND
  CB7_A  = M_F_CPU0_SA_CB<7>
  VSS89  = GND
  RESET_N  = RST_M_EF_CPU0_FPGA_N
  VSS90  = GND
  CS1_A_N  = M_F_CPU0_SA_CS_N<1>
  VSS91  = GND
  CA1_A  = M_F_CPU0_SA_CA<1>
  VSS92  = GND
  CA3_A  = M_F_CPU0_SA_CA<3>
  VSS93  = GND
  CA5_A  = M_F_CPU0_SA_CA<5>
  VSS94  = GND
  CK_T  = M_F_CPU0_CLK_DP<0>
  CK_C  = M_F_CPU0_CLK_DN<0>
  VSS95  = GND
  RFU4  = TP_CHF_CPU0_DIMM1_FRU_4
  CA1_B  = M_F_CPU0_SB_CA<1>
  VSS96  = GND
  CA3_B  = M_F_CPU0_SB_CA<3>
  VSS97  = GND
  CA5_B  = M_F_CPU0_SB_CA<5>
  VSS98  = GND
  PAR_B  = M_F_CPU0_SB_PAR
  VSS99  = GND
  CS1_B_N  = M_F_CPU0_SB_CS_N<1>
  VSS100  = GND
  RFU5  = TP_CHF_CPU0_DIMM1_FRU_5
  RFU6  = TP_CHF_CPU0_DIMM1_FRU_6
  VSS101  = GND
  CB6_B  = M_F_CPU0_SB_CB<6>
  VSS102  = GND
  CB7_B  = M_F_CPU0_SB_CB<7>
  VSS103  = GND
  DQS4_B_C  = M_F_CPU0_SB_DQS_DN<4>
  DQS4_B_T  = M_F_CPU0_SB_DQS_DP<4>
  VSS104  = GND
  CB2_B  = M_F_CPU0_SB_CB<2>
  VSS105  = GND
  CB3_B  = M_F_CPU0_SB_CB<3>
  VSS106  = GND
  DQ2_B  = M_F_CPU0_SB_DQ<2>
  VSS107  = GND
  DQ3_B  = M_F_CPU0_SB_DQ<3>
  VSS108  = GND
  \dqs5_b_c||tdqs5_b_c\  = M_F_CPU0_SB_DQS_DN<5>
  \dqs5_b_t||tdqs5_b_t\  = M_F_CPU0_SB_DQS_DP<5>
  VSS109  = GND
  DQ6_B  = M_F_CPU0_SB_DQ<6>
  VSS110  = GND
  DQ7_B  = M_F_CPU0_SB_DQ<7>
  VSS111  = GND
  DQ10_B  = M_F_CPU0_SB_DQ<10>
  VSS112  = GND
  DQ11_B  = M_F_CPU0_SB_DQ<11>
  VSS113  = GND
  \dqs6_b_c||tdqs6_b_c\  = M_F_CPU0_SB_DQS_DN<6>
  \dqs6_b_t||tdqs6_b_t\  = M_F_CPU0_SB_DQS_DP<6>
  VSS114  = GND
  DQ14_B  = M_F_CPU0_SB_DQ<14>
  VSS115  = GND
  DQ15_B  = M_F_CPU0_SB_DQ<15>
  VSS116  = GND
  DQ18_B  = M_F_CPU0_SB_DQ<18>
  VSS117  = GND
  DQ19_B  = M_F_CPU0_SB_DQ<19>
  VSS118  = GND
  \dqs7_b_c||tdqs7_b_c\  = M_F_CPU0_SB_DQS_DN<7>
  \dqs7_b_t||tdqs7_b_t\  = M_F_CPU0_SB_DQS_DP<7>
  VSS119  = GND
  DQ22_B  = M_F_CPU0_SB_DQ<22>
  VSS120  = GND
  DQ23_B  = M_F_CPU0_SB_DQ<23>
  VSS121  = GND
  DQ26_B  = M_F_CPU0_SB_DQ<26>
  VSS122  = GND
  DQ27_B  = M_F_CPU0_SB_DQ<27>
  VSS123  = GND
  \dqs8_b_c||tdqs8_b_c\  = M_F_CPU0_SB_DQS_DN<8>
  \dqs8_b_t||tdqs8_b_t\  = M_F_CPU0_SB_DQS_DP<8>
  VSS124  = GND
  DQ30_B  = M_F_CPU0_SB_DQ<30>
  VSS125  = GND
  DQ31_B  = M_F_CPU0_SB_DQ<31>
  VSS126  = GND
  G1  = GND
  G2  = GND
  G3  = GND

(kicad_pcb
	(version 20260206)
	(generator "pcbnew")
	(generator_version "10.0")
	(general
		(thickness 1.6)
		(legacy_teardrops no)
	)
	(paper "A4")
	(title_block
		(title "03242023_DA0F0TMBIJ0_F0T_Motherboard_J_brd_V01_OCP.brd")
		(comment 1 "Grand Teton / footprint 1952 of 6105 (J11), pads 92-137 of 291")
	)
	(layers
		(0 "F.Cu" signal "TOP")
		(4 "In1.Cu" signal "GND")
		(6 "In2.Cu" signal "IN1")
		(8 "In3.Cu" signal "GND1")
		(10 "In4.Cu" signal "IN2")
		(12 "In5.Cu" signal "GND2")
		(14 "In6.Cu" signal "IN3")
		(16 "In7.Cu" signal "GND3")
		(18 "In8.Cu" signal "VCC")
		(20 "In9.Cu" signal "VCC1")
		(22 "In10.Cu" signal "GND4")
		(24 "In11.Cu" signal "IN4")
		(26 "In12.Cu" signal "GND5")
		(28 "In13.Cu" signal "IN5")
		(30 "In14.Cu" signal "GND6")
		(32 "In15.Cu" signal "IN6")
		(34 "In16.Cu" signal "GND7")
		(2 "B.Cu" signal "BOTTOM")
		(9 "F.Adhes" user "F.Adhesive")
		(11 "B.Adhes" user "B.Adhesive")
		(13 "F.Paste" user "Package Geometry/Pastemask Top")
		(15 "B.Paste" user "Package Geometry/Pastemask Bottom")
		(5 "F.SilkS" user "Ref Des/Silkscreen Top")
		(7 "B.SilkS" user "Ref Des/Silkscreen Bottom")
		(1 "F.Mask" user "Board Geometry/Soldermask Top")
		(3 "B.Mask" user "Board Geometry/Soldermask Bottom")
		(17 "Dwgs.User" user "User.Drawings")
		(19 "Cmts.User" user "User.Comments")
		(21 "Eco1.User" user "User.Eco1")
		(23 "Eco2.User" user "User.Eco2")
		(25 "Edge.Cuts" user "Board Geometry/Outline")
		(27 "Margin" user)
		(31 "F.CrtYd" user "Package Geometry/Place Bound Top")
		(29 "B.CrtYd" user "Package Geometry/Place Bound Bottom")
		(35 "F.Fab" user "Ref Des/Assembly Top")
		(33 "B.Fab" user "Ref Des/Assembly Bottom")
	)
	(footprint ""
		(layer "F.Cu")
		(at 431.434748 -258.091686)
		(property "Reference" "J11"
			(at -3.683 -81.702148 0)
			(unlocked yes)
			(layer "F.SilkS")
			(effects
				(font
					(size 0.7874 0.5842)
					(thickness 0.1524)
				)
				(justify left)
			)
		)
		(property "Value" ""
			(at 0 0 0)
			(layer "F.Fab")
			(effects
				(font
					(size 1.27 1.27)
				)
			)
		)
		(duplicate_pad_numbers_are_jumpers no)
		(pad "92" smd rect
			(at -2.050034 19.12493 270)
			(size 0.519938 1.4986)
			(layers "F.Cu" "F.Mask" "F.Paste")
			(net "GND")
		)
		(pad "93" smd rect
			(at -2.050034 19.975068 270)
			(size 0.519938 1.4986)
			(layers "F.Cu" "F.Mask" "F.Paste")
			(net "M_F_CPU0_SB_DQS_DP<9>")
		)
		(pad "94" smd rect
			(at -2.050034 20.824952 270)
			(size 0.519938 1.4986)
			(layers "F.Cu" "F.Mask" "F.Paste")
			(net "M_F_CPU0_SB_DQS_DN<9>")
		)
		(pad "95" smd rect
			(at -2.050034 21.67509 270)
			(size 0.519938 1.4986)
			(layers "F.Cu" "F.Mask" "F.Paste")
			(net "GND")
		)
		(pad "96" smd rect
			(at -2.050034 22.524974 270)
			(size 0.519938 1.4986)
			(layers "F.Cu" "F.Mask" "F.Paste")
			(net "M_F_CPU0_SB_CB<0>")
		)
		(pad "97" smd rect
			(at -2.050034 23.375112 270)
			(size 0.519938 1.4986)
			(layers "F.Cu" "F.Mask" "F.Paste")
			(net "GND")
		)
		(pad "98" smd rect
			(at -2.050034 24.224996 270)
			(size 0.519938 1.4986)
			(layers "F.Cu" "F.Mask" "F.Paste")
			(net "M_F_CPU0_SB_CB<1>")
		)
		(pad "99" smd rect
			(at -2.050034 25.07488 270)
			(size 0.519938 1.4986)
			(layers "F.Cu" "F.Mask" "F.Paste")
			(net "GND")
		)
		(pad "100" smd rect
			(at -2.050034 25.925018 270)
			(size 0.519938 1.4986)
			(layers "F.Cu" "F.Mask" "F.Paste")
			(net "M_F_CPU0_SB_DQ<0>")
		)
		(pad "101" smd rect
			(at -2.050034 26.774902 270)
			(size 0.519938 1.4986)
			(layers "F.Cu" "F.Mask" "F.Paste")
			(net "GND")
		)
		(pad "102" smd rect
			(at -2.050034 27.62504 270)
			(size 0.519938 1.4986)
			(layers "F.Cu" "F.Mask" "F.Paste")
			(net "M_F_CPU0_SB_DQ<1>")
		)
		(pad "103" smd rect
			(at -2.050034 28.474924 270)
			(size 0.519938 1.4986)
			(layers "F.Cu" "F.Mask" "F.Paste")
			(net "GND")
		)
		(pad "104" smd rect
			(at -2.050034 29.325062 270)
			(size 0.519938 1.4986)
			(layers "F.Cu" "F.Mask" "F.Paste")
			(net "M_F_CPU0_SB_DQS_DP<0>")
		)
		(pad "105" smd rect
			(at -2.050034 30.174946 270)
			(size 0.519938 1.4986)
			(layers "F.Cu" "F.Mask" "F.Paste")
			(net "M_F_CPU0_SB_DQS_DN<0>")
		)
		(pad "106" smd rect
			(at -2.050034 31.025084 270)
			(size 0.519938 1.4986)
			(layers "F.Cu" "F.Mask" "F.Paste")
			(net "GND")
		)
		(pad "107" smd rect
			(at -2.050034 31.874968 270)
			(size 0.519938 1.4986)
			(layers "F.Cu" "F.Mask" "F.Paste")
			(net "M_F_CPU0_SB_DQ<4>")
		)
		(pad "108" smd rect
			(at -2.050034 32.725106 270)
			(size 0.519938 1.4986)
			(layers "F.Cu" "F.Mask" "F.Paste")
			(net "GND")
		)
		(pad "109" smd rect
			(at -2.050034 33.57499 270)
			(size 0.519938 1.4986)
			(layers "F.Cu" "F.Mask" "F.Paste")
			(net "M_F_CPU0_SB_DQ<5>")
		)
		(pad "110" smd rect
			(at -2.050034 34.425128 270)
			(size 0.519938 1.4986)
			(layers "F.Cu" "F.Mask" "F.Paste")
			(net "GND")
		)
		(pad "111" smd rect
			(at -2.050034 35.275012 270)
			(size 0.519938 1.4986)
			(layers "F.Cu" "F.Mask" "F.Paste")
			(net "M_F_CPU0_SB_DQ<8>")
		)
		(pad "112" smd rect
			(at -2.050034 36.124896 270)
			(size 0.519938 1.4986)
			(layers "F.Cu" "F.Mask" "F.Paste")
			(net "GND")
		)
		(pad "113" smd rect
			(at -2.050034 36.975034 270)
			(size 0.519938 1.4986)
			(layers "F.Cu" "F.Mask" "F.Paste")
			(net "M_F_CPU0_SB_DQ<9>")
		)
		(pad "114" smd rect
			(at -2.050034 37.824918 270)
			(size 0.519938 1.4986)
			(layers "F.Cu" "F.Mask" "F.Paste")
			(net "GND")
		)
		(pad "115" smd rect
			(at -2.050034 38.675056 270)
			(size 0.519938 1.4986)
			(layers "F.Cu" "F.Mask" "F.Paste")
			(net "M_F_CPU0_SB_DQS_DP<1>")
		)
		(pad "116" smd rect
			(at -2.050034 39.52494 270)
			(size 0.519938 1.4986)
			(layers "F.Cu" "F.Mask" "F.Paste")
			(net "M_F_CPU0_SB_DQS_DN<1>")
		)
		(pad "117" smd rect
			(at -2.050034 40.375078 270)
			(size 0.519938 1.4986)
			(layers "F.Cu" "F.Mask" "F.Paste")
			(net "GND")
		)
		(pad "118" smd rect
			(at -2.050034 41.224962 270)
			(size 0.519938 1.4986)
			(layers "F.Cu" "F.Mask" "F.Paste")
			(net "M_F_CPU0_SB_DQ<12>")
		)
		(pad "119" smd rect
			(at -2.050034 42.0751 270)
			(size 0.519938 1.4986)
			(layers "F.Cu" "F.Mask" "F.Paste")
			(net "GND")
		)
		(pad "120" smd rect
			(at -2.050034 42.924984 270)
			(size 0.519938 1.4986)
			(layers "F.Cu" "F.Mask" "F.Paste")
			(net "M_F_CPU0_SB_DQ<13>")
		)
		(pad "121" smd rect
			(at -2.050034 43.775122 270)
			(size 0.519938 1.4986)
			(layers "F.Cu" "F.Mask" "F.Paste")
			(net "GND")
		)
		(pad "122" smd rect
			(at -2.050034 44.625006 270)
			(size 0.519938 1.4986)
			(layers "F.Cu" "F.Mask" "F.Paste")
			(net "M_F_CPU0_SB_DQ<16>")
		)
		(pad "123" smd rect
			(at -2.050034 45.47489 270)
			(size 0.519938 1.4986)
			(layers "F.Cu" "F.Mask" "F.Paste")
			(net "GND")
		)
		(pad "124" smd rect
			(at -2.050034 46.325028 270)
			(size 0.519938 1.4986)
			(layers "F.Cu" "F.Mask" "F.Paste")
			(net "M_F_CPU0_SB_DQ<17>")
		)
		(pad "125" smd rect
			(at -2.050034 47.174912 270)
			(size 0.519938 1.4986)
			(layers "F.Cu" "F.Mask" "F.Paste")
			(net "GND")
		)
		(pad "126" smd rect
			(at -2.050034 48.02505 270)
			(size 0.519938 1.4986)
			(layers "F.Cu" "F.Mask" "F.Paste")
			(net "M_F_CPU0_SB_DQS_DP<2>")
		)
		(pad "127" smd rect
			(at -2.050034 48.874934 270)
			(size 0.519938 1.4986)
			(layers "F.Cu" "F.Mask" "F.Paste")
			(net "M_F_CPU0_SB_DQS_DN<2>")
		)
		(pad "128" smd rect
			(at -2.050034 49.725072 270)
			(size 0.519938 1.4986)
			(layers "F.Cu" "F.Mask" "F.Paste")
			(net "GND")
		)
		(pad "129" smd rect
			(at -2.050034 50.574956 270)
			(size 0.519938 1.4986)
			(layers "F.Cu" "F.Mask" "F.Paste")
			(net "M_F_CPU0_SB_DQ<20>")
		)
		(pad "130" smd rect
			(at -2.050034 51.425094 270)
			(size 0.519938 1.4986)
			(layers "F.Cu" "F.Mask" "F.Paste")
			(net "GND")
		)
		(pad "131" smd rect
			(at -2.050034 52.274978 270)
			(size 0.519938 1.4986)
			(layers "F.Cu" "F.Mask" "F.Paste")
			(net "M_F_CPU0_SB_DQ<21>")
		)
		(pad "132" smd rect
			(at -2.050034 53.125116 270)
			(size 0.519938 1.4986)
			(layers "F.Cu" "F.Mask" "F.Paste")
			(net "GND")
		)
		(pad "133" smd rect
			(at -2.050034 53.975 270)
			(size 0.519938 1.4986)
			(layers "F.Cu" "F.Mask" "F.Paste")
			(net "M_F_CPU0_SB_DQ<24>")
		)
		(pad "134" smd rect
			(at -2.050034 54.824884 270)
			(size 0.519938 1.4986)
			(layers "F.Cu" "F.Mask" "F.Paste")
			(net "GND")
		)
		(pad "135" smd rect
			(at -2.050034 55.675022 270)
			(size 0.519938 1.4986)
			(layers "F.Cu" "F.Mask" "F.Paste")
			(net "M_F_CPU0_SB_DQ<25>")
		)
		(pad "136" smd rect
			(at -2.050034 56.524906 270)
			(size 0.519938 1.4986)
			(layers "F.Cu" "F.Mask" "F.Paste")
			(net "GND")
		)
		(pad "137" smd rect
			(at -2.050034 57.375044 270)
			(size 0.519938 1.4986)
			(layers "F.Cu" "F.Mask" "F.Paste")
			(net "M_F_CPU0_SB_DQS_DP<3>")
		)
	)
)
